(kicad_pcb
	(version 20260206)
	(generator "pcbnew")
	(generator_version "10.0")
	(general
		(thickness 1.6)
		(legacy_teardrops no)
	)
	(paper "A4")
	(title_block
		(title "01162023_DA0F0TEBIF0_F0T_Expander_BD_F_brd_V02_OCP.brd")
		(comment 1 "Grand Teton / footprints 2905-2910 of 9728")
	)
	(layers
		(0 "F.Cu" signal "TOP")
		(4 "In1.Cu" signal "GND")
		(6 "In2.Cu" signal "VCC")
		(8 "In3.Cu" signal "VCC1")
		(10 "In4.Cu" signal "GND1")
		(12 "In5.Cu" signal "IN1")
		(14 "In6.Cu" signal "GND2")
		(16 "In7.Cu" signal "IN2")
		(18 "In8.Cu" signal "GND3")
		(20 "In9.Cu" signal "IN3")
		(22 "In10.Cu" signal "GND4")
		(24 "In11.Cu" signal "IN4")
		(26 "In12.Cu" signal "GND5")
		(28 "In13.Cu" signal "IN5")
		(30 "In14.Cu" signal "GND6")
		(32 "In15.Cu" signal "IN6")
		(34 "In16.Cu" signal "GND7")
		(2 "B.Cu" signal "BOTTOM")
		(9 "F.Adhes" user "F.Adhesive")
		(11 "B.Adhes" user "B.Adhesive")
		(13 "F.Paste" user "Package Geometry/Pastemask Top")
		(15 "B.Paste" user "Package Geometry/Pastemask Bottom")
		(5 "F.SilkS" user "Ref Des/Silkscreen Top")
		(7 "B.SilkS" user "Ref Des/Silkscreen Bottom")
		(1 "F.Mask" user "Board Geometry/Soldermask Top")
		(3 "B.Mask" user "Board Geometry/Soldermask Bottom")
		(17 "Dwgs.User" user "User.Drawings")
		(19 "Cmts.User" user "User.Comments")
		(21 "Eco1.User" user "User.Eco1")
		(23 "Eco2.User" user "User.Eco2")
		(25 "Edge.Cuts" user "Board Geometry/Outline")
		(27 "Margin" user)
		(31 "F.CrtYd" user "Package Geometry/Place Bound Top")
		(29 "B.CrtYd" user "Package Geometry/Place Bound Bottom")
		(35 "F.Fab" user "Ref Des/Assembly Top")
		(33 "B.Fab" user "Ref Des/Assembly Bottom")
	)
	(footprint ""
		(layer "F.Cu")
		(at 22.408388 -257.102102)
		(property "Reference" "Q12"
			(at -1.218438 -4.390136 90)
			(unlocked yes)
			(layer "F.SilkS")
			(effects
				(font
					(size 0.7874 0.5842)
					(thickness 0.1524)
				)
			)
		)
		(property "Value" ""
			(at 0 0 0)
			(layer "F.Fab")
			(effects
				(font
					(size 1.27 1.27)
				)
			)
		)
		(duplicate_pad_numbers_are_jumpers no)
		(fp_line
			(start -1.376172 -1.199896)
			(end -0.508 -1.199896)
			(stroke
				(width 0.1524)
				(type default)
			)
			(layer "F.SilkS")
		)
		(fp_line
			(start -1.376172 1.199896)
			(end -1.376172 -1.199896)
			(stroke
				(width 0.1524)
				(type default)
			)
			(layer "F.SilkS")
		)
		(fp_line
			(start -0.508 -1.199896)
			(end 0 -0.762)
			(stroke
				(width 0.1524)
				(type default)
			)
			(layer "F.SilkS")
		)
		(fp_line
			(start 0 -0.762)
			(end 0.508 -1.199896)
			(stroke
				(width 0.1524)
				(type default)
			)
			(layer "F.SilkS")
		)
		(fp_line
			(start 0.508 -1.199896)
			(end 1.376172 -1.199896)
			(stroke
				(width 0.1524)
				(type default)
			)
			(layer "F.SilkS")
		)
		(fp_line
			(start 1.376172 -1.199896)
			(end 1.376172 1.199896)
			(stroke
				(width 0.1524)
				(type default)
			)
			(layer "F.SilkS")
		)
		(fp_line
			(start 1.376172 1.199896)
			(end -1.376172 1.199896)
			(stroke
				(width 0.1524)
				(type default)
			)
			(layer "F.SilkS")
		)
		(fp_poly
			(pts
				(xy -1.4605 -0.7493) (xy -2.2225 -1.1303) (xy -2.2225 -0.3683)
			)
			(stroke
				(width 0)
				(type default)
			)
			(fill yes)
			(layer "F.SilkS")
		)
		(fp_line
			(start -0.674878 -1.100074)
			(end 0.674878 -1.100074)
			(stroke
				(width 0.1)
				(type default)
			)
			(layer "F.Fab")
		)
		(fp_line
			(start -0.674878 1.100074)
			(end -0.674878 -1.100074)
			(stroke
				(width 0.1)
				(type default)
			)
			(layer "F.Fab")
		)
		(fp_line
			(start 0.674878 -1.100074)
			(end 0.674878 1.100074)
			(stroke
				(width 0.1)
				(type default)
			)
			(layer "F.Fab")
		)
		(fp_line
			(start 0.674878 1.100074)
			(end -0.674878 1.100074)
			(stroke
				(width 0.1)
				(type default)
			)
			(layer "F.Fab")
		)
		(fp_poly
			(pts
				(xy -1.4605 -0.7493) (xy -2.2225 -1.1303) (xy -2.2225 -0.3683)
			)
			(stroke
				(width 0)
				(type default)
			)
			(fill yes)
			(layer "F.Fab")
		)
		(pad "1" smd rect
			(at -0.899922 -0.750062 270)
			(size 0.6096 0.6096)
			(layers "F.Cu" "F.Mask" "F.Paste")
			(net "GND")
		)
		(pad "2" smd rect
			(at -0.899922 0 270)
			(size 0.4064 0.6096)
			(layers "F.Cu" "F.Mask" "F.Paste")
			(net "PEX0_SYS_ERR_R_N")
		)
		(pad "3" smd rect
			(at -0.899922 0.750062 270)
			(size 0.6096 0.6096)
			(layers "F.Cu" "F.Mask" "F.Paste")
			(net "PEX0_SYS_ERR_3V3_N")
		)
		(pad "4" smd rect
			(at 0.899922 0.750062 270)
			(size 0.6096 0.6096)
			(layers "F.Cu" "F.Mask" "F.Paste")
			(net "GND")
		)
		(pad "5" smd rect
			(at 0.899922 0 270)
			(size 0.4064 0.6096)
			(layers "F.Cu" "F.Mask" "F.Paste")
			(net "PEX0_SYS_ERR_N_G")
		)
		(pad "6" smd rect
			(at 0.899922 -0.750062 270)
			(size 0.6096 0.6096)
			(layers "F.Cu" "F.Mask" "F.Paste")
			(net "PEX0_SYS_ERR_N_G")
		)
	)
	(footprint ""
		(layer "F.Cu")
		(at 214.194136 -179.848256 -90)
		(property "Reference" "R5419"
			(at 0 0 270)
			(layer "F.SilkS")
			(hide yes)
			(effects
				(font
					(size 1.27 1.27)
				)
			)
		)
		(property "Value" ""
			(at 0 0 270)
			(layer "F.Fab")
			(effects
				(font
					(size 1.27 1.27)
				)
			)
		)
		(duplicate_pad_numbers_are_jumpers no)
		(fp_line
			(start -0.7874 0.4064)
			(end -0.7874 -0.4064)
			(stroke
				(width 0.1524)
				(type default)
			)
			(layer "F.SilkS")
		)
		(fp_line
			(start 0.7874 0.4064)
			(end -0.7874 0.4064)
			(stroke
				(width 0.1524)
				(type default)
			)
			(layer "F.SilkS")
		)
		(fp_line
			(start -0.7874 -0.4064)
			(end 0.7874 -0.4064)
			(stroke
				(width 0.1524)
				(type default)
			)
			(layer "F.SilkS")
		)
		(fp_line
			(start 0.7874 -0.4064)
			(end 0.7874 0.4064)
			(stroke
				(width 0.1524)
				(type default)
			)
			(layer "F.SilkS")
		)
		(fp_line
			(start -0.67945 0.3048)
			(end -0.67945 -0.305054)
			(stroke
				(width 0.1)
				(type default)
			)
			(layer "F.Fab")
		)
		(fp_line
			(start -0.12065 0.3048)
			(end -0.67945 0.3048)
			(stroke
				(width 0.1)
				(type default)
			)
			(layer "F.Fab")
		)
		(fp_line
			(start 0.120396 0.3048)
			(end 0.120396 0.2794)
			(stroke
				(width 0.1)
				(type default)
			)
			(layer "F.Fab")
		)
		(fp_line
			(start 0.67945 0.3048)
			(end 0.120396 0.3048)
			(stroke
				(width 0.1)
				(type default)
			)
			(layer "F.Fab")
		)
		(fp_line
			(start -0.12065 0.2794)
			(end -0.12065 0.3048)
			(stroke
				(width 0.1)
				(type default)
			)
			(layer "F.Fab")
		)
		(fp_line
			(start 0.120396 0.2794)
			(end -0.12065 0.2794)
			(stroke
				(width 0.1)
				(type default)
			)
			(layer "F.Fab")
		)
		(fp_line
			(start -0.12065 -0.2794)
			(end 0.12065 -0.2794)
			(stroke
				(width 0.1)
				(type default)
			)
			(layer "F.Fab")
		)
		(fp_line
			(start 0.12065 -0.2794)
			(end 0.12065 -0.3048)
			(stroke
				(width 0.1)
				(type default)
			)
			(layer "F.Fab")
		)
		(fp_line
			(start 0.12065 -0.3048)
			(end 0.67945 -0.3048)
			(stroke
				(width 0.1)
				(type default)
			)
			(layer "F.Fab")
		)
		(fp_line
			(start 0.67945 -0.3048)
			(end 0.67945 0.3048)
			(stroke
				(width 0.1)
				(type default)
			)
			(layer "F.Fab")
		)
		(fp_line
			(start -0.67945 -0.305054)
			(end -0.12065 -0.305054)
			(stroke
				(width 0.1)
				(type default)
			)
			(layer "F.Fab")
		)
		(fp_line
			(start -0.12065 -0.305054)
			(end -0.12065 -0.2794)
			(stroke
				(width 0.1)
				(type default)
			)
			(layer "F.Fab")
		)
		(pad "1" smd circle
			(at -0.40005 0 270)
			(size 0 0)
			(layers "F.Cu" "F.Mask" "F.Paste")
			(net "SEL_FLASH_PEX1_BUF_R")
		)
		(pad "2" smd circle
			(at 0.40005 0 270)
			(size 0 0)
			(layers "F.Cu" "F.Mask" "F.Paste")
			(net "P3V3_AUX")
		)
	)
	(footprint ""
		(layer "F.Cu")
		(at 58.995056 -101.782372 180)
		(property "Reference" "R72"
			(at 0 0 180)
			(layer "F.SilkS")
			(hide yes)
			(effects
				(font
					(size 1.27 1.27)
				)
			)
		)
		(property "Value" ""
			(at 0 0 180)
			(layer "F.Fab")
			(effects
				(font
					(size 1.27 1.27)
				)
			)
		)
		(duplicate_pad_numbers_are_jumpers no)
		(fp_line
			(start 0.7874 0.4064)
			(end -0.7874 0.4064)
			(stroke
				(width 0.1524)
				(type default)
			)
			(layer "F.SilkS")
		)
		(fp_line
			(start 0.7874 -0.4064)
			(end 0.7874 0.4064)
			(stroke
				(width 0.1524)
				(type default)
			)
			(layer "F.SilkS")
		)
		(fp_line
			(start -0.7874 0.4064)
			(end -0.7874 -0.4064)
			(stroke
				(width 0.1524)
				(type default)
			)
			(layer "F.SilkS")
		)
		(fp_line
			(start -0.7874 -0.4064)
			(end 0.7874 -0.4064)
			(stroke
				(width 0.1524)
				(type default)
			)
			(layer "F.SilkS")
		)
		(fp_line
			(start 0.67945 0.3048)
			(end 0.120396 0.3048)
			(stroke
				(width 0.1)
				(type default)
			)
			(layer "F.Fab")
		)
		(fp_line
			(start 0.67945 -0.3048)
			(end 0.67945 0.3048)
			(stroke
				(width 0.1)
				(type default)
			)
			(layer "F.Fab")
		)
		(fp_line
			(start 0.12065 -0.2794)
			(end 0.12065 -0.3048)
			(stroke
				(width 0.1)
				(type default)
			)
			(layer "F.Fab")
		)
		(fp_line
			(start 0.12065 -0.3048)
			(end 0.67945 -0.3048)
			(stroke
				(width 0.1)
				(type default)
			)
			(layer "F.Fab")
		)
		(fp_line
			(start 0.120396 0.3048)
			(end 0.120396 0.2794)
			(stroke
				(width 0.1)
				(type default)
			)
			(layer "F.Fab")
		)
		(fp_line
			(start 0.120396 0.2794)
			(end -0.12065 0.2794)
			(stroke
				(width 0.1)
				(type default)
			)
			(layer "F.Fab")
		)
		(fp_line
			(start -0.12065 0.3048)
			(end -0.67945 0.3048)
			(stroke
				(width 0.1)
				(type default)
			)
			(layer "F.Fab")
		)
		(fp_line
			(start -0.12065 0.2794)
			(end -0.12065 0.3048)
			(stroke
				(width 0.1)
				(type default)
			)
			(layer "F.Fab")
		)
		(fp_line
			(start -0.12065 -0.2794)
			(end 0.12065 -0.2794)
			(stroke
				(width 0.1)
				(type default)
			)
			(layer "F.Fab")
		)
		(fp_line
			(start -0.12065 -0.305054)
			(end -0.12065 -0.2794)
			(stroke
				(width 0.1)
				(type default)
			)
			(layer "F.Fab")
		)
		(fp_line
			(start -0.67945 0.3048)
			(end -0.67945 -0.305054)
			(stroke
				(width 0.1)
				(type default)
			)
			(layer "F.Fab")
		)
		(fp_line
			(start -0.67945 -0.305054)
			(end -0.12065 -0.305054)
			(stroke
				(width 0.1)
				(type default)
			)
			(layer "F.Fab")
		)
		(pad "1" smd circle
			(at -0.40005 0 180)
			(size 0 0)
			(layers "F.Cu" "F.Mask" "F.Paste")
			(net "NCSI_NIC1_TX_EN")
		)
		(pad "2" smd circle
			(at 0.40005 0 180)
			(size 0 0)
			(layers "F.Cu" "F.Mask" "F.Paste")
			(net "GND")
		)
	)
	(footprint ""
		(layer "F.Cu")
		(at 202.829668 -300.62043 90)
		(property "Reference" "R6390"
			(at 0 0 90)
			(layer "F.SilkS")
			(hide yes)
			(effects
				(font
					(size 1.27 1.27)
				)
			)
		)
		(property "Value" ""
			(at 0 0 90)
			(layer "F.Fab")
			(effects
				(font
					(size 1.27 1.27)
				)
			)
		)
		(duplicate_pad_numbers_are_jumpers no)
		(fp_line
			(start 0.7874 -0.4064)
			(end 0.7874 0.4064)
			(stroke
				(width 0.1524)
				(type default)
			)
			(layer "F.SilkS")
		)
		(fp_line
			(start -0.7874 -0.4064)
			(end 0.7874 -0.4064)
			(stroke
				(width 0.1524)
				(type default)
			)
			(layer "F.SilkS")
		)
		(fp_line
			(start 0.7874 0.4064)
			(end -0.7874 0.4064)
			(stroke
				(width 0.1524)
				(type default)
			)
			(layer "F.SilkS")
		)
		(fp_line
			(start -0.7874 0.4064)
			(end -0.7874 -0.4064)
			(stroke
				(width 0.1524)
				(type default)
			)
			(layer "F.SilkS")
		)
		(fp_line
			(start -0.12065 -0.305054)
			(end -0.12065 -0.2794)
			(stroke
				(width 0.1)
				(type default)
			)
			(layer "F.Fab")
		)
		(fp_line
			(start -0.67945 -0.305054)
			(end -0.12065 -0.305054)
			(stroke
				(width 0.1)
				(type default)
			)
			(layer "F.Fab")
		)
		(fp_line
			(start 0.67945 -0.3048)
			(end 0.67945 0.3048)
			(stroke
				(width 0.1)
				(type default)
			)
			(layer "F.Fab")
		)
		(fp_line
			(start 0.12065 -0.3048)
			(end 0.67945 -0.3048)
			(stroke
				(width 0.1)
				(type default)
			)
			(layer "F.Fab")
		)
		(fp_line
			(start 0.12065 -0.2794)
			(end 0.12065 -0.3048)
			(stroke
				(width 0.1)
				(type default)
			)
			(layer "F.Fab")
		)
		(fp_line
			(start -0.12065 -0.2794)
			(end 0.12065 -0.2794)
			(stroke
				(width 0.1)
				(type default)
			)
			(layer "F.Fab")
		)
		(fp_line
			(start 0.120396 0.2794)
			(end -0.12065 0.2794)
			(stroke
				(width 0.1)
				(type default)
			)
			(layer "F.Fab")
		)
		(fp_line
			(start -0.12065 0.2794)
			(end -0.12065 0.3048)
			(stroke
				(width 0.1)
				(type default)
			)
			(layer "F.Fab")
		)
		(fp_line
			(start 0.67945 0.3048)
			(end 0.120396 0.3048)
			(stroke
				(width 0.1)
				(type default)
			)
			(layer "F.Fab")
		)
		(fp_line
			(start 0.120396 0.3048)
			(end 0.120396 0.2794)
			(stroke
				(width 0.1)
				(type default)
			)
			(layer "F.Fab")
		)
		(fp_line
			(start -0.12065 0.3048)
			(end -0.67945 0.3048)
			(stroke
				(width 0.1)
				(type default)
			)
			(layer "F.Fab")
		)
		(fp_line
			(start -0.67945 0.3048)
			(end -0.67945 -0.305054)
			(stroke
				(width 0.1)
				(type default)
			)
			(layer "F.Fab")
		)
		(pad "1" smd circle
			(at -0.40005 0 90)
			(size 0 0)
			(layers "F.Cu" "F.Mask" "F.Paste")
			(net "RST_PEX1_S3_PERST_N")
		)
		(pad "2" smd circle
			(at 0.40005 0 90)
			(size 0 0)
			(layers "F.Cu" "F.Mask" "F.Paste")
			(net "RST_PEX1_S3_PERST_R_N")
		)
	)
	(footprint ""
		(layer "F.Cu")
		(at 59.007756 -212.5726)
		(property "Reference" "J71"
			(at -1.4224 -4.562348 0)
			(unlocked yes)
			(layer "F.SilkS")
			(effects
				(font
					(size 0.7874 0.5842)
					(thickness 0.1524)
				)
				(justify left)
			)
		)
		(property "Value" ""
			(at 0 0 0)
			(layer "F.Fab")
			(effects
				(font
					(size 1.27 1.27)
				)
			)
		)
		(duplicate_pad_numbers_are_jumpers no)
		(fp_line
			(start -1.27 -3.81)
			(end 1.27 -3.81)
			(stroke
				(width 0.1524)
				(type default)
			)
			(layer "F.SilkS")
		)
		(fp_line
			(start -1.27 -0.7747)
			(end -1.27 -3.81)
			(stroke
				(width 0.1524)
				(type default)
			)
			(layer "F.SilkS")
		)
		(fp_line
			(start -1.27 3.81)
			(end -1.27 0.7747)
			(stroke
				(width 0.1524)
				(type default)
			)
			(layer "F.SilkS")
		)
		(fp_line
			(start 1.27 -3.81)
			(end 1.27 -3.3147)
			(stroke
				(width 0.1524)
				(type default)
			)
			(layer "F.SilkS")
		)
		(fp_line
			(start 1.27 -1.7653)
			(end 1.27 1.7653)
			(stroke
				(width 0.1524)
				(type default)
			)
			(layer "F.SilkS")
		)
		(fp_line
			(start 1.27 3.3147)
			(end 1.27 3.81)
			(stroke
				(width 0.1524)
				(type default)
			)
			(layer "F.SilkS")
		)
		(fp_line
			(start 1.27 3.81)
			(end -1.27 3.81)
			(stroke
				(width 0.1524)
				(type default)
			)
			(layer "F.SilkS")
		)
		(fp_poly
			(pts
				(xy 4.3942 -3.048) (xy 4.3942 -2.032) (xy 3.3782 -2.54)
			)
			(stroke
				(width 0)
				(type default)
			)
			(fill yes)
			(layer "F.SilkS")
		)
		(fp_line
			(start -1.27 -3.81)
			(end -1.27 3.81)
			(stroke
				(width 0.1)
				(type default)
			)
			(layer "F.Fab")
		)
		(fp_line
			(start -1.27 3.81)
			(end 1.27 3.81)
			(stroke
				(width 0.1)
				(type default)
			)
			(layer "F.Fab")
		)
		(fp_line
			(start 1.27 -3.81)
			(end -1.27 -3.81)
			(stroke
				(width 0.1)
				(type default)
			)
			(layer "F.Fab")
		)
		(fp_line
			(start 1.27 3.81)
			(end 1.27 -3.81)
			(stroke
				(width 0.1)
				(type default)
			)
			(layer "F.Fab")
		)
		(fp_poly
			(pts
				(xy 4.3942 -3.048) (xy 4.3942 -2.032) (xy 3.3782 -2.54)
			)
			(stroke
				(width 0)
				(type default)
			)
			(fill yes)
			(layer "F.Fab")
		)
		(fp_text user "3"
			(at 3.921252 2.54 90)
			(unlocked yes)
			(layer "F.SilkS")
			(effects
				(font
					(size 0.7874 0.5842)
					(thickness 0.1524)
				)
			)
		)
		(fp_text user "3"
			(at 3.921252 2.54 90)
			(unlocked yes)
			(layer "F.Fab")
			(effects
				(font
					(size 0.7874 0.5842)
					(thickness 0.1524)
				)
			)
		)
		(pad "1" smd rect
			(at 1.459992 -2.54 90)
			(size 1.27 3.429)
			(layers "F.Cu" "F.Mask" "F.Paste")
			(net "GND")
		)
		(pad "2" smd rect
			(at -1.459992 0 90)
			(size 1.27 3.429)
			(layers "F.Cu" "F.Mask" "F.Paste")
			(net "UART_PEX2_CLI_BUF_R1_TX")
		)
		(pad "3" smd rect
			(at 1.459992 2.54 90)
			(size 1.27 3.429)
			(layers "F.Cu" "F.Mask" "F.Paste")
			(net "UART_PEX2_CLI_R1_RX")
		)
	)
	(footprint ""
		(layer "F.Cu")
		(at 30.153356 -294.591232)
		(property "Reference" "L90"
			(at 0 0 0)
			(layer "F.SilkS")
			(hide yes)
			(effects
				(font
					(size 1.27 1.27)
				)
			)
		)
		(property "Value" ""
			(at 0 0 0)
			(layer "F.Fab")
			(effects
				(font
					(size 1.27 1.27)
				)
			)
		)
		(duplicate_pad_numbers_are_jumpers no)
		(fp_line
			(start -1.63576 -0.8128)
			(end -1.63576 0.8128)
			(stroke
				(width 0.1524)
				(type default)
			)
			(layer "F.SilkS")
		)
		(fp_line
			(start -1.63576 -0.8128)
			(end 1.63576 -0.8128)
			(stroke
				(width 0.1524)
				(type default)
			)
			(layer "F.SilkS")
		)
		(fp_line
			(start 1.63576 -0.8128)
			(end 1.63576 0.8128)
			(stroke
				(width 0.1524)
				(type default)
			)
			(layer "F.SilkS")
		)
		(fp_line
			(start 1.63576 0.8128)
			(end -1.63576 0.8128)
			(stroke
				(width 0.1524)
				(type default)
			)
			(layer "F.SilkS")
		)
		(fp_line
			(start -1.56083 -0.738632)
			(end -1.56083 0.7366)
			(stroke
				(width 0.1)
				(type default)
			)
			(layer "F.Fab")
		)
		(fp_line
			(start -1.56083 0.7366)
			(end -1.524 0.7366)
			(stroke
				(width 0.1)
				(type default)
			)
			(layer "F.Fab")
		)
		(fp_line
			(start -1.524 0.7366)
			(end 1.524 0.7366)
			(stroke
				(width 0.1)
				(type default)
			)
			(layer "F.Fab")
		)
		(fp_line
			(start 1.524 0.7366)
			(end 1.560576 0.7366)
			(stroke
				(width 0.1)
				(type default)
			)
			(layer "F.Fab")
		)
		(fp_line
			(start 1.560576 -0.738632)
			(end -1.56083 -0.738632)
			(stroke
				(width 0.1)
				(type default)
			)
			(layer "F.Fab")
		)
		(fp_line
			(start 1.560576 0.7366)
			(end 1.560576 -0.738632)
			(stroke
				(width 0.1)
				(type default)
			)
			(layer "F.Fab")
		)
		(pad "1" smd rect
			(at -0.94996 0 180)
			(size 1.1176 1.3716)
			(layers "F.Cu" "F.Mask" "F.Paste")
			(net "P1V8_PLL0_PEX0")
		)
		(pad "2" smd rect
			(at 0.94996 0 180)
			(size 1.1176 1.3716)
			(layers "F.Cu" "F.Mask" "F.Paste")
			(net "PCEPLL2_VDDA18_PEX0")
		)
	)
)
